# T6G (Grand Teton) — schematic netlist excerpt (pin names and nets, part order shuffled) for the footprints in the layout excerpt that follows; sources: Cadence DE-HDL packaged netlist, KiCad conversion of 04192023_DAF0TMB3IC0_F0TG_MB_C_brd_V02_OCP.brd

C56  Q_CAP_DIFFBUS  DIFF BUS_0.22UF 6.3V 20% X6S  pkg C0201  page 67 : \1\ = P5E_CPU1_G1_TX_C_DP<8> ; \2\ = P5E_CPU1_G1_TX_DP<8>
PC1525  Q_CAP  1UF 25V 10% X6S  pkg C0402  page 263 : A = HSC_VDD_R_1 ; B = AGND_HSC
R3609  Q_RES  4.7K 1% EMPTY  pkg 0402LF  page 237 : A = GND ; B = INA230_3_A0

(kicad_pcb
	(version 20260206)
	(generator "pcbnew")
	(generator_version "10.0")
	(general
		(thickness 1.6)
		(legacy_teardrops no)
	)
	(paper "A4")
	(title_block
		(title "04192023_DAF0TMB3IC0_F0TG_MB_C_brd_V02_OCP.brd")
		(comment 1 "Grand Teton / footprints 1811-1813 of 8354")
	)
	(layers
		(0 "F.Cu" signal "TOP")
		(4 "In1.Cu" signal "GND")
		(6 "In2.Cu" signal "IN1")
		(8 "In3.Cu" signal "GND1")
		(10 "In4.Cu" signal "IN2")
		(12 "In5.Cu" signal "GND2")
		(14 "In6.Cu" signal "IN3")
		(16 "In7.Cu" signal "GND3")
		(18 "In8.Cu" signal "VCC")
		(20 "In9.Cu" signal "VCC1")
		(22 "In10.Cu" signal "GND4")
		(24 "In11.Cu" signal "IN4")
		(26 "In12.Cu" signal "GND5")
		(28 "In13.Cu" signal "IN5")
		(30 "In14.Cu" signal "GND6")
		(32 "In15.Cu" signal "IN6")
		(34 "In16.Cu" signal "GND7")
		(2 "B.Cu" signal "BOTTOM")
		(9 "F.Adhes" user "F.Adhesive")
		(11 "B.Adhes" user "B.Adhesive")
		(13 "F.Paste" user "Package Geometry/Pastemask Top")
		(15 "B.Paste" user "Package Geometry/Pastemask Bottom")
		(5 "F.SilkS" user "Ref Des/Silkscreen Top")
		(7 "B.SilkS" user "Ref Des/Silkscreen Bottom")
		(1 "F.Mask" user "Board Geometry/Soldermask Top")
		(3 "B.Mask" user "Board Geometry/Soldermask Bottom")
		(17 "Dwgs.User" user "User.Drawings")
		(19 "Cmts.User" user "User.Comments")
		(21 "Eco1.User" user "User.Eco1")
		(23 "Eco2.User" user "User.Eco2")
		(25 "Edge.Cuts" user "Board Geometry/Outline")
		(27 "Margin" user)
		(31 "F.CrtYd" user "Package Geometry/Place Bound Top")
		(29 "B.CrtYd" user "Package Geometry/Place Bound Bottom")
		(35 "F.Fab" user "Ref Des/Assembly Top")
		(33 "B.Fab" user "Ref Des/Assembly Bottom")
	)
	(footprint ""
		(layer "F.Cu")
		(at 35.980878 -17.623536 90)
		(property "Reference" "C56"
			(at 0 0 90)
			(layer "F.SilkS")
			(hide yes)
			(effects
				(font
					(size 1.27 1.27)
				)
			)
		)
		(property "Value" ""
			(at 0 0 90)
			(layer "F.Fab")
			(effects
				(font
					(size 1.27 1.27)
				)
			)
		)
		(duplicate_pad_numbers_are_jumpers no)
		(fp_line
			(start 0.299974 -0.150114)
			(end 0.299974 0.150114)
			(stroke
				(width 0.1)
				(type default)
			)
			(layer "F.Fab")
		)
		(fp_line
			(start -0.299974 -0.150114)
			(end 0.299974 -0.150114)
			(stroke
				(width 0.1)
				(type default)
			)
			(layer "F.Fab")
		)
		(fp_line
			(start 0.299974 0.150114)
			(end -0.299974 0.150114)
			(stroke
				(width 0.1)
				(type default)
			)
			(layer "F.Fab")
		)
		(fp_line
			(start -0.299974 0.150114)
			(end -0.299974 -0.150114)
			(stroke
				(width 0.1)
				(type default)
			)
			(layer "F.Fab")
		)
		(pad "1" smd rect
			(at -0.2667 0 90)
			(size 0.3048 0.381)
			(layers "F.Cu" "F.Mask" "F.Paste")
			(net "P5E_CPU1_G1_TX_C_DP<8>")
		)
		(pad "2" smd rect
			(at 0.2667 0 90)
			(size 0.3048 0.381)
			(layers "F.Cu" "F.Mask" "F.Paste")
			(net "P5E_CPU1_G1_TX_DP<8>")
		)
	)
	(footprint ""
		(layer "F.Cu")
		(at 68.212462 -39.421562)
		(property "Reference" "R3609"
			(at 0 0 0)
			(layer "F.SilkS")
			(hide yes)
			(effects
				(font
					(size 1.27 1.27)
				)
			)
		)
		(property "Value" ""
			(at 0 0 0)
			(layer "F.Fab")
			(effects
				(font
					(size 1.27 1.27)
				)
			)
		)
		(duplicate_pad_numbers_are_jumpers no)
		(fp_line
			(start -0.7874 -0.4064)
			(end 0.7874 -0.4064)
			(stroke
				(width 0.1524)
				(type default)
			)
			(layer "F.SilkS")
		)
		(fp_line
			(start -0.7874 0.4064)
			(end -0.7874 -0.4064)
			(stroke
				(width 0.1524)
				(type default)
			)
			(layer "F.SilkS")
		)
		(fp_line
			(start 0.7874 -0.4064)
			(end 0.7874 0.4064)
			(stroke
				(width 0.1524)
				(type default)
			)
			(layer "F.SilkS")
		)
		(fp_line
			(start 0.7874 0.4064)
			(end -0.7874 0.4064)
			(stroke
				(width 0.1524)
				(type default)
			)
			(layer "F.SilkS")
		)
		(fp_line
			(start -0.67945 -0.305054)
			(end -0.12065 -0.305054)
			(stroke
				(width 0.1)
				(type default)
			)
			(layer "F.Fab")
		)
		(fp_line
			(start -0.67945 0.3048)
			(end -0.67945 -0.305054)
			(stroke
				(width 0.1)
				(type default)
			)
			(layer "F.Fab")
		)
		(fp_line
			(start -0.12065 -0.305054)
			(end -0.12065 -0.2794)
			(stroke
				(width 0.1)
				(type default)
			)
			(layer "F.Fab")
		)
		(fp_line
			(start -0.12065 -0.2794)
			(end 0.12065 -0.2794)
			(stroke
				(width 0.1)
				(type default)
			)
			(layer "F.Fab")
		)
		(fp_line
			(start -0.12065 0.2794)
			(end -0.12065 0.3048)
			(stroke
				(width 0.1)
				(type default)
			)
			(layer "F.Fab")
		)
		(fp_line
			(start -0.12065 0.3048)
			(end -0.67945 0.3048)
			(stroke
				(width 0.1)
				(type default)
			)
			(layer "F.Fab")
		)
		(fp_line
			(start 0.120396 0.2794)
			(end -0.12065 0.2794)
			(stroke
				(width 0.1)
				(type default)
			)
			(layer "F.Fab")
		)
		(fp_line
			(start 0.120396 0.3048)
			(end 0.120396 0.2794)
			(stroke
				(width 0.1)
				(type default)
			)
			(layer "F.Fab")
		)
		(fp_line
			(start 0.12065 -0.3048)
			(end 0.67945 -0.3048)
			(stroke
				(width 0.1)
				(type default)
			)
			(layer "F.Fab")
		)
		(fp_line
			(start 0.12065 -0.2794)
			(end 0.12065 -0.3048)
			(stroke
				(width 0.1)
				(type default)
			)
			(layer "F.Fab")
		)
		(fp_line
			(start 0.67945 -0.3048)
			(end 0.67945 0.3048)
			(stroke
				(width 0.1)
				(type default)
			)
			(layer "F.Fab")
		)
		(fp_line
			(start 0.67945 0.3048)
			(end 0.120396 0.3048)
			(stroke
				(width 0.1)
				(type default)
			)
			(layer "F.Fab")
		)
		(pad "1" smd circle
			(at -0.40005 0)
			(size 0 0)
			(layers "F.Cu" "F.Mask" "F.Paste")
			(net "GND")
		)
		(pad "2" smd circle
			(at 0.40005 0)
			(size 0 0)
			(layers "F.Cu" "F.Mask" "F.Paste")
			(net "INA230_3_A0")
		)
	)
	(footprint ""
		(layer "F.Cu")
		(at 195.6943 -401.963382 90)
		(property "Reference" "PC1525"
			(at 0 0 90)
			(layer "F.SilkS")
			(hide yes)
			(effects
				(font
					(size 1.27 1.27)
				)
			)
		)
		(property "Value" ""
			(at 0 0 90)
			(layer "F.Fab")
			(effects
				(font
					(size 1.27 1.27)
				)
			)
		)
		(duplicate_pad_numbers_are_jumpers no)
		(fp_line
			(start 0.7874 -0.4064)
			(end 0.7874 0.4064)
			(stroke
				(width 0.1524)
				(type default)
			)
			(layer "F.SilkS")
		)
		(fp_line
			(start -0.7874 -0.4064)
			(end 0.7874 -0.4064)
			(stroke
				(width 0.1524)
				(type default)
			)
			(layer "F.SilkS")
		)
		(fp_line
			(start 0.7874 0.4064)
			(end -0.7874 0.4064)
			(stroke
				(width 0.1524)
				(type default)
			)
			(layer "F.SilkS")
		)
		(fp_line
			(start -0.7874 0.4064)
			(end -0.7874 -0.4064)
			(stroke
				(width 0.1524)
				(type default)
			)
			(layer "F.SilkS")
		)
		(fp_line
			(start -0.12065 -0.305054)
			(end -0.12065 -0.2794)
			(stroke
				(width 0.1)
				(type default)
			)
			(layer "F.Fab")
		)
		(fp_line
			(start -0.67945 -0.305054)
			(end -0.12065 -0.305054)
			(stroke
				(width 0.1)
				(type default)
			)
			(layer "F.Fab")
		)
		(fp_line
			(start 0.67945 -0.3048)
			(end 0.67945 0.3048)
			(stroke
				(width 0.1)
				(type default)
			)
			(layer "F.Fab")
		)
		(fp_line
			(start 0.12065 -0.3048)
			(end 0.67945 -0.3048)
			(stroke
				(width 0.1)
				(type default)
			)
			(layer "F.Fab")
		)
		(fp_line
			(start 0.12065 -0.2794)
			(end 0.12065 -0.3048)
			(stroke
				(width 0.1)
				(type default)
			)
			(layer "F.Fab")
		)
		(fp_line
			(start -0.12065 -0.2794)
			(end 0.12065 -0.2794)
			(stroke
				(width 0.1)
				(type default)
			)
			(layer "F.Fab")
		)
		(fp_line
			(start 0.120396 0.2794)
			(end -0.12065 0.2794)
			(stroke
				(width 0.1)
				(type default)
			)
			(layer "F.Fab")
		)
		(fp_line
			(start -0.12065 0.2794)
			(end -0.12065 0.3048)
			(stroke
				(width 0.1)
				(type default)
			)
			(layer "F.Fab")
		)
		(fp_line
			(start 0.67945 0.3048)
			(end 0.120396 0.3048)
			(stroke
				(width 0.1)
				(type default)
			)
			(layer "F.Fab")
		)
		(fp_line
			(start 0.120396 0.3048)
			(end 0.120396 0.2794)
			(stroke
				(width 0.1)
				(type default)
			)
			(layer "F.Fab")
		)
		(fp_line
			(start -0.12065 0.3048)
			(end -0.67945 0.3048)
			(stroke
				(width 0.1)
				(type default)
			)
			(layer "F.Fab")
		)
		(fp_line
			(start -0.67945 0.3048)
			(end -0.67945 -0.305054)
			(stroke
				(width 0.1)
				(type default)
			)
			(layer "F.Fab")
		)
		(pad "1" smd circle
			(at -0.40005 0 90)
			(size 0 0)
			(layers "F.Cu" "F.Mask" "F.Paste")
			(net "HSC_VDD_R_1")
		)
		(pad "2" smd circle
			(at 0.40005 0 90)
			(size 0 0)
			(layers "F.Cu" "F.Mask" "F.Paste")
			(net "AGND_HSC")
		)
	)
)
